FILE_TYPE = CONNECTIVITY;
{Allegro Design Entry HDL 17.4-2019 S026 (4007227) 1/17/2022}
"PAGE_NUMBER" = 184;
0"NC";
1"GND\g";
2"GND\g";
3"P3V3_AUX\g";
4"GND\g";
5"GND\g";
6"GND\g";
7"P3V3_AUX\g";
8"GND\g";
9"GND\g";
10"GND\g";
11"GND\g";
12"PVDD18_S5_P0_EN";
13"GND\g";
14"SW_P12V_AUX_PVDD18_S5_P0_FLT";
15"P12V_AUX\g";
16"PVDD18_S5_P0\g";
17"GND\g";
18"GND\g";
19"PWRGD_PVDD18_S5_P0";
20"SW_PVDD18_S5_P0_SW";
21"PVDD18_S5_P0_CS";
22"PVDD18_S5_P0_REF";
23"FM_PWRGD_PVDD18_S5_P0";
24"VSENSE_PVDD18_S5_P0_DP";
25"VSENSE_PVDD18_S5_P0_DN";
26"PVDD18_S5_P0_FB_RC";
27"PVDD18_S5_P0_VCC";
28"PVDD18_S5_P0_MODE";
29"PVDD18_S5_P0_RGND";
30"PVDD18_S5_P0_FB";
31"SW_PVDD18_S5_P0_BST";
32"SW_PVDD18_S5_P0_BST_R";
%"UNIVERSAL_GND"
"1","(-9225,3825)","0","pure_quanta_power","I1";
;
CDS_LIB"pure_quanta_power"
HDL_POWER"GND";
"A"1;
%"UNIVERSAL_GND"
"1","(-7575,2325)","0","pure_quanta_power","I10";
;
CDS_LIB"pure_quanta_power"
HDL_POWER"GND";
"A"2;
%"Q_CAP"
"1","(-7575,2550)","2","pure_quanta","I11";
;
LOCATION"PC212"
SEC"1"
TOLERANCE"10%"
VOLTAGE"25V"
PACK_TYPE"C0402"
VALUE"1UF"
MATERIAL"X6S"
CDS_LIB"pure_quanta"
SIGNAL_MODEL"DEFAULT_CAPACITOR_100000PF_2_1"
SEC_TYPE"C0402"
PART_NUMBER"CH5104KEB02";
"B"
$PN"2"2;
"A"
$PN"1"27;
%"Q_RES"
"2","(-7575,2975)","0","pure_quanta","I12";
;
LOCATION"PR477"
$SEC"1"
CDS_SEC"1"
WATTAGE"1/16W"
MATERIAL"CHIP"
TOLERANCE"5%"
VALUE"0"
PACK_TYPE"0402LF"
CDS_LIB"pure_quanta"
PART_NUMBER"CS00002JB13";
"A"
$PN"1"3;
"B"
$PN"2"27;
%"UNIVERSAL_GND"
"1","(-7950,3750)","0","pure_quanta_power","I13";
;
CDS_LIB"pure_quanta_power"
HDL_POWER"GND";
"A"13;
%"UNIVERSAL_POWER"
"1","(-7575,3175)","0","mstr_symbols","I14";
;
HDL_POWER"P3V3_AUX"
CDS_LIB"mstr_symbols";
"A"3;
%"Q_RES"
"1","(-7075,3375)","0","pure_quanta","I15";
;
LOCATION"PR417"
$SEC"1"
CDS_SEC"1"
PACK_TYPE"0402LF"
WATTAGE"1/16W"
MATERIAL"CHIP"
TOLERANCE"5%"
VALUE"0"
CDS_LIB"pure_quanta"
PART_NUMBER"CS00002JB13";
"B"
$PN"2"28;
"A"
$PN"1"11;
%"UNIVERSAL_GND"
"1","(-6700,2300)","0","pure_quanta_power","I16";
;
CDS_LIB"pure_quanta_power"
HDL_POWER"GND";
"A"4;
%"Q_RES"
"2","(-6700,2550)","0","pure_quanta","I17";
;
LOCATION"PR448"
SEC"1"
WATTAGE"1/16W"
MATERIAL"CHIP"
TOLERANCE"1%"
VALUE"8.66K"
PACK_TYPE"0402LF"
CDS_LIB"pure_quanta"
SEC_TYPE"0402LF"
PART_NUMBER"CS28662FB02";
"A"
$PN"1"21;
"B"
$PN"2"4;
%"MPQ8633BGLEC838Z"
"1","(-5750,3400)","0","pure_quanta","I18";
;
LOCATION"PU57"
$SEC"1"
CDS_SEC"1"
MATERIAL"IC"
VALUE"MPQ8633BGLE-C838-Z"
PART_TYPE"SMLF"
CDS_LMAN_SYM_OUTLINE"-250,725,250,-725"
NEEDS_NO_SIZE"TRUE"
CDS_LIB"pure_quanta"
PART_NUMBER"AL008633005";
"VIN2"
$PN"21"14;
"CS"
$PN"3"21;
"MODE"
$PN"4"28;
"TRK_REF"
$PN"5"22;
"SW"
$PN"20"20;
"RGND"
$PN"6"29;
"VCC"
$PN"19"27;
"AGND"
$PN"2"18;
"FB"
$PN"7"30;
"BST"
$PN"1"31;
"EN"
$PN"8"12;
"PGND"
$PN"11_18"18;
"PGOOD"
$PN"9"19;
"VIN1"
$PN"10"14;
%"UNIVERSAL_GND"
"1","(-5125,2450)","0","pure_quanta_power","I19";
;
CDS_LIB"pure_quanta_power"
HDL_POWER"GND";
"A"18;
%"UNIVERSAL_GND"
"1","(-5000,2450)","0","pure_quanta_power","I20";
;
CDS_LIB"pure_quanta_power"
HDL_POWER"GND";
"A"5;
%"Q_CAP"
"1","(-5000,2700)","0","pure_quanta","I21";
;
LOCATION"PC258"
$SEC"1"
CDS_SEC"1"
VALUE"0.022UF"
MATERIAL"X7R"
PACK_TYPE"0402"
VOLTAGE"25V"
TOLERANCE"10%"
CDS_LIB"pure_quanta"
PART_NUMBER"CH3224K1B01";
"B"
$PN"2"5;
"A"
$PN"1"22;
%"Q_CAP"
"1","(-4575,2875)","1","pure_quanta","I22";
;
LOCATION"PC113"
$SEC"1"
CDS_SEC"1"
PACK_TYPE"0402"
TOLERANCE"10%"
MATERIAL"X7R"
VALUE"0.1UF"
VOLTAGE"25V"
CDS_LIB"pure_quanta"
PART_NUMBER"CH4104K1B00";
"B"
$PN"2"29;
"A"
$PN"1"22;
%"Q_RES"
"2","(-4150,2600)","0","pure_quanta","I23";
;
LOCATION"PR470"
$SEC"1"
CDS_SEC"1"
VALUE"10K"
MATERIAL"CHIP"
TOLERANCE"1%"
WATTAGE"1/16W"
PACK_TYPE"0402LF"
CDS_LIB"pure_quanta"
PART_NUMBER"CS31002FB08";
"A"
$PN"1"30;
"B"
$PN"2"29;
%"Q_CAP"
"1","(-4100,3725)","0","pure_quanta","I24";
;
LOCATION"PC209"
SEC"1"
PACK_TYPE"0402"
MATERIAL"X7R"
VALUE"0.22UF"
VOLTAGE"16V"
TOLERANCE"10%"
SEC_TYPE"0402"
CDS_LIB"pure_quanta"
PART_NUMBER"CH4223K1B00";
"B"
$PN"2"20;
"A"
$PN"1"32;
%"Q_CAP"
"1","(-7575,4125)","0","pure_quanta","I25";
;
LOCATION"PC227"
$SEC"1"
CDS_SEC"1"
PACK_TYPE"C0805"
VOLTAGE"16V"
TOLERANCE"20%"
MATERIAL"X6S"
VALUE"22UF"
CDS_LIB"pure_quanta"
PART_NUMBER"CH6223MEA01";
"B"
$PN"2"13;
"A"
$PN"1"14;
%"Q_CAP"
"1","(-7225,4125)","0","pure_quanta","I26";
;
LOCATION"PC254"
$SEC"1"
CDS_SEC"1"
PACK_TYPE"C0805"
MATERIAL"X6S"
TOLERANCE"20%"
VOLTAGE"16V"
VALUE"22UF"
CDS_LIB"pure_quanta"
PART_NUMBER"CH6223MEA01";
"B"
$PN"2"13;
"A"
$PN"1"14;
%"Q_CAP"
"1","(-6975,4125)","0","pure_quanta","I27";
;
LOCATION"PC81"
$SEC"1"
CDS_SEC"1"
PACK_TYPE"C0805"
MATERIAL"X6S"
VALUE"22UF"
VOLTAGE"16V"
TOLERANCE"20%"
CDS_LIB"pure_quanta"
PART_NUMBER"CH6223MEA01";
"B"
$PN"2"13;
"A"
$PN"1"14;
%"Q_CAP"
"1","(-6725,4125)","0","pure_quanta","I28";
;
LOCATION"PC237"
$SEC"1"
CDS_SEC"1"
MATERIAL"X6S"
PACK_TYPE"C0402"
VALUE"1UF"
VOLTAGE"25V"
TOLERANCE"10%"
CDS_LIB"pure_quanta"
PART_NUMBER"CH5104KEB02";
"B"
$PN"2"13;
"A"
$PN"1"14;
%"Q_RES"
"2","(-4700,4375)","0","pure_quanta","I29";
;
LOCATION"R8465"
SEC"1"
WATTAGE"1/16W"
VALUE"10K"
TOLERANCE"5%"
PACK_TYPE"0402LF"
MATERIAL"CHIP"
CDS_LIB"pure_quanta"
SEC_TYPE"0402LF"
PART_NUMBER"CS31002JB08";
"A"
$PN"1"7;
"B"
$PN"2"19;
%"UNIVERSAL_GND"
"1","(-8575,3175)","0","pure_quanta_power","I3";
;
CDS_LIB"pure_quanta_power"
HDL_POWER"GND";
"A"6;
%"UNIVERSAL_POWER"
"1","(-4700,4650)","0","mstr_symbols","I30";
;
HDL_POWER"P3V3_AUX"
CDS_LIB"mstr_symbols";
"A"7;
%"Q_RES"
"1","(-3575,1775)","1","pure_quanta","I31";
;
LOCATION"PR418"
$SEC"1"
CDS_SEC"1"
TOLERANCE"1%"
VALUE"49.9"
PACK_TYPE"0402LF"
MATERIAL"CHIP"
WATTAGE"1/16W"
CDS_LIB"pure_quanta"
PART_NUMBER"CS04992FB07";
"B"
$PN"2"29;
"A"
$PN"1"8;
%"UNIVERSAL_GND"
"1","(-3575,1525)","0","pure_quanta_power","I32";
;
CDS_LIB"pure_quanta_power"
HDL_POWER"GND";
"A"8;
%"Q_CAP"
"2","(-3575,2800)","0","pure_quanta","I33";
;
LOCATION"PC259"
$SEC"1"
CDS_SEC"1"
TOLERANCE"10%"
VOLTAGE"50V"
VALUE"220PF"
MATERIAL"X7R"
PACK_TYPE"0402"
CDS_LIB"pure_quanta"
PART_NUMBER"TMP_QCH12206KB14";
"A"
$PN"1"30;
"B"
$PN"2"26;
%"Q_CAP"
"1","(-3150,2175)","0","pure_quanta","I34";
;
LOCATION"PC6005"
$SEC"1"
CDS_SEC"1"
VALUE"0.01UF"
VOLTAGE"25V"
MATERIAL"EMPTY"
TOLERANCE"10%"
PACK_TYPE"C0402"
CDS_LIB"pure_quanta"
PART_NUMBER"CH3104K1B11";
"B"
$PN"2"29;
"A"
$PN"1"26;
%"Q_RES"
"1","(-3575,3125)","0","pure_quanta","I35";
;
LOCATION"PR471"
$SEC"1"
CDS_SEC"1"
PACK_TYPE"0402LF"
MATERIAL"CHIP"
VALUE"20K"
CDS_LIB"pure_quanta"
WATTAGE"1/16W"
TOLERANCE"1%"
PART_NUMBER"CS32002FB06";
"B"
$PN"2"26;
"A"
$PN"1"30;
%"Q_INDUCTOR"
"1","(-3575,3600)","0","pure_quanta","I36";
;
LOCATION"PL78"
$SEC"1"
CDS_SEC"1"
MATERIAL"IND"
PACK_TYPE"SMLF"
VALUE"1.0UH/18A"
NEEDS_NO_SIZE"TRUE"
CDS_LIB"pure_quanta"
PART_NUMBER"CV-10I0MZ01";
"1"
$PN"1"20;
"2"
$PN"2"16;
%"Q_RES"
"2","(-2600,2025)","1","pure_quanta","I37";
;
LOCATION"PR435"
$SEC"1"
CDS_SEC"1"
PACK_TYPE"0402LF"
WATTAGE"1/16W"
VALUE"0"
TOLERANCE"5%"
MATERIAL"CHIP"
CDS_LIB"pure_quanta"
PART_NUMBER"CS00002JB13";
"A"
$PN"1"29;
"B"
$PN"2"25;
%"Q_RES"
"1","(-2600,2325)","0","pure_quanta","I38";
;
LOCATION"PR434"
$SEC"1"
CDS_SEC"1"
VALUE"10"
TOLERANCE"1%"
MATERIAL"CHIP"
PACK_TYPE"0402LF"
WATTAGE"1/16W"
CDS_LIB"pure_quanta"
PART_NUMBER"CS01002FB07";
"B"
$PN"2"24;
"A"
$PN"1"26;
%"Q_CAP"
"1","(-2925,3325)","0","pure_quanta","I39";
;
LOCATION"PC114"
$SEC"1"
CDS_SEC"1"
MATERIAL"X6S"
PACK_TYPE"C0805"
TOLERANCE"20%"
VALUE"22UF"
VOLTAGE"4V"
CDS_LIB"pure_quanta"
PART_NUMBER"CH622KMEA03";
"B"
$PN"2"17;
"A"
$PN"1"16;
%"Q_CAP"
"1","(-8575,3375)","2","pure_quanta","I4";
;
LOCATION"C674"
$SEC"1"
CDS_SEC"1"
MATERIAL"EMPTY"
TOLERANCE"10%"
PACK_TYPE"0402"
VALUE"0.1UF"
VOLTAGE"25V"
CDS_LIB"pure_quanta"
PART_NUMBER"CH4104K1B00";
"B"
$PN"2"6;
"A"
$PN"1"12;
%"Q_CAP"
"1","(-2275,3325)","0","pure_quanta","I40";
;
LOCATION"PC288"
$SEC"1"
CDS_SEC"1"
MATERIAL"X6S"
TOLERANCE"20%"
VALUE"22UF"
VOLTAGE"4V"
PACK_TYPE"C0805"
CDS_LIB"pure_quanta"
PART_NUMBER"CH622KMEA03";
"B"
$PN"2"17;
"A"
$PN"1"16;
%"Q_CAP"
"1","(-2025,3325)","0","pure_quanta","I41";
;
LOCATION"PC260"
$SEC"1"
CDS_SEC"1"
VALUE"22UF"
VOLTAGE"4V"
TOLERANCE"20%"
PACK_TYPE"C0805"
MATERIAL"EMPTY"
CDS_LIB"pure_quanta"
PART_NUMBER"CH622KMEA03";
"B"
$PN"2"17;
"A"
$PN"1"16;
%"Q_RES"
"1","(-1700,2825)","0","pure_quanta","I42";
;
LOCATION"PR438"
$SEC"1"
CDS_SEC"1"
PACK_TYPE"0402LF"
VALUE"49.9"
TOLERANCE"1%"
WATTAGE"1/16W"
MATERIAL"CHIP"
CDS_LIB"pure_quanta"
PART_NUMBER"CS04992FB07";
"B"
$PN"2"16;
"A"
$PN"1"26;
%"UNIVERSAL_GND"
"1","(-1100,2950)","0","pure_quanta_power","I45";
;
CDS_LIB"pure_quanta_power"
HDL_POWER"GND";
"A"17;
%"Q_CAP"
"1","(-1700,3325)","0","pure_quanta","I46";
;
LOCATION"PC261"
$SEC"1"
CDS_SEC"1"
PACK_TYPE"C0805"
MATERIAL"EMPTY"
TOLERANCE"20%"
VALUE"22UF"
VOLTAGE"4V"
CDS_LIB"pure_quanta"
PART_NUMBER"CH622KMEA03";
"B"
$PN"2"17;
"A"
$PN"1"16;
%"Q_CAPP"
"1","(-1425,3325)","0","pure_quanta","I47";
;
LOCATION"PC115"
$SEC"1"
CDS_SEC"1"
MATERIAL"ALUM"
TOLERANCE"20%"
VALUE"390UF"
VOLTAGE"2.5V"
PACK_TYPE"SMLF"
CDS_LIB"pure_quanta"
PART_NUMBER"CC7390JMZ13";
"A"
$PN"1"16;
"B"
$PN"2"17;
%"Q_CAP"
"1","(-1100,3325)","0","pure_quanta","I48";
;
LOCATION"PC215"
SEC"1"
PACK_TYPE"0402"
VOLTAGE"25V"
VALUE"0.1UF"
TOLERANCE"10%"
MATERIAL"X7R"
SEC_TYPE"0402"
CDS_LIB"pure_quanta"
PART_NUMBER"CH4104K1B00";
"B"
$PN"2"17;
"A"
$PN"1"16;
%"UNIVERSAL_GND"
"1","(-500,2775)","0","pure_quanta_power","I49";
;
CDS_LIB"pure_quanta_power"
HDL_POWER"GND";
"A"9;
%"Q_CAP"
"1","(-9225,4150)","0","pure_quanta","I5";
;
LOCATION"PC6001"
$SEC"1"
CDS_SEC"1"
PACK_TYPE"C0402"
TOLERANCE"10%"
VALUE"0.1UF"
VOLTAGE"25V"
MATERIAL"X6S"
CDS_LIB"pure_quanta"
PART_NUMBER"CH4104KEB00";
"B"
$PN"2"1;
"A"
$PN"1"15;
%"P1V0"
"1","(-500,3950)","0","pure_quanta_power","I50";
;
HDL_POWER"PVDD18_S5_P0"
CDS_LIB"pure_quanta_power";
"A"16;
%"Q_RES"
"2","(-500,3300)","0","pure_quanta","I51";
;
LOCATION"PR439"
$SEC"1"
CDS_SEC"1"
WATTAGE"1/16W"
MATERIAL"CHIP"
TOLERANCE"1%"
VALUE"1K"
PACK_TYPE"0402LF"
CDS_LIB"pure_quanta"
PART_NUMBER"CS21002FB06";
"A"
$PN"1"16;
"B"
$PN"2"9;
%"Q_RES"
"1","(-3650,4075)","0","pure_quanta","I52";
;
LOCATION"R177"
$SEC"1"
CDS_SEC"1"
VALUE"33"
PACK_TYPE"0402LF"
TOLERANCE"5%"
MATERIAL"CHIP"
WATTAGE"1/16W"
BOM_COST"MEM"
CDS_LIB"pure_quanta"
PART_NUMBER"CS03302JB10";
"B"
$PN"2"23;
"A"
$PN"1"19;
%"Q_CAP"
"1","(-2475,3325)","0","pure_quanta","I54";
;
LOCATION"PC285"
$SEC"1"
CDS_SEC"1"
MATERIAL"X6S"
VOLTAGE"4V"
TOLERANCE"20%"
PACK_TYPE"C0805"
VALUE"22UF"
CDS_LIB"pure_quanta"
PART_NUMBER"CH622KMEA03";
"B"
$PN"2"17;
"A"
$PN"1"16;
%"UNIVERSAL_GND"
"1","(-2850,3725)","0","pure_quanta_power","I55";
;
CDS_LIB"pure_quanta_power"
HDL_POWER"GND";
"A"10;
%"Q_CAP"
"1","(-2850,3925)","0","pure_quanta","I56";
;
LOCATION"C5001"
$SEC"1"
CDS_SEC"1"
PACK_TYPE"0402"
VALUE"1000PF"
VOLTAGE"50V"
MATERIAL"X7R"
TOLERANCE"5%"
CDS_LIB"pure_quanta"
PART_NUMBER"TMP_QCH21006JB10";
"B"
$PN"2"10;
"A"
$PN"1"23;
%"Q_CAP"
"1","(-8200,4125)","0","pure_quanta","I57";
;
LOCATION"PC8002"
$SEC"1"
CDS_SEC"1"
VALUE"22UF"
MATERIAL"X6S"
VOLTAGE"16V"
TOLERANCE"20%"
PACK_TYPE"C0805"
CDS_LIB"pure_quanta"
PART_NUMBER"CH6223MEA01";
"B"
$PN"2"13;
"A"
$PN"1"14;
%"Q_RES"
"1","(-4550,3875)","0","pure_quanta","I58";
;
LOCATION"PR8001"
SEC"1"
PACK_TYPE"0402LF"
TOLERANCE"1%"
MATERIAL"CHIP"
VALUE"2.2"
SEC_TYPE"0402LF"
CDS_LIB"pure_quanta"
WATTAGE"1/16W"
PART_NUMBER"CS-2202FB01";
"B"
$PN"2"32;
"A"
$PN"1"31;
%"P1V0_AUX"
"1","(-9225,4550)","0","mstr_symbols","I6";
;
HDL_POWER"P12V_AUX"
CDS_LIB"mstr_symbols"
VOLTAGE"1.0V"
ROOM"VR_DDR1_POWER_STAGE"
BODY_TYPE"PLUMBING";
"A"15;
%"Q_INDUCTOR"
"1","(-8875,4375)","0","pure_quanta","I7";
;
LOCATION"PL77"
$SEC"1"
CDS_SEC"1"
VALUE"BLM18SN220TN1D/8000MA"
PACK_TYPE"SMLF"
MATERIAL"IND"
NEEDS_NO_SIZE"TRUE"
CDS_LIB"pure_quanta"
PART_NUMBER"CX220TN1001";
"1"
$PN"1"15;
"2"
$PN"2"14;
%"Q_CAP"
"1","(-7875,4125)","0","pure_quanta","I8";
;
LOCATION"PC111"
$SEC"1"
CDS_SEC"1"
VALUE"22UF"
PACK_TYPE"C0805"
MATERIAL"X6S"
VOLTAGE"16V"
TOLERANCE"20%"
CDS_LIB"pure_quanta"
PART_NUMBER"CH6223MEA01";
"B"
$PN"2"13;
"A"
$PN"1"14;
%"UNIVERSAL_GND"
"1","(-8050,2925)","0","pure_quanta_power","I9";
;
CDS_LIB"pure_quanta_power"
HDL_POWER"GND";
"A"11;
END.
